(kicad_pcb
	(version 20260206)
	(generator "pcbnew")
	(generator_version "10.0")
	(general
		(thickness 1.6)
		(legacy_teardrops no)
	)
	(paper "A4")
	(title_block
		(title "Wiwynn_Tioga_Pass_MB.brd")
		(comment 1 "Tioga Pass / footprints 4226-4232 of 4770")
	)
	(layers
		(0 "F.Cu" signal "TOP")
		(4 "In1.Cu" signal "L2GND")
		(6 "In2.Cu" signal "L3")
		(8 "In3.Cu" signal "L4GND")
		(10 "In4.Cu" signal "L5")
		(12 "In5.Cu" signal "L6GND")
		(14 "In6.Cu" signal "L7VCC")
		(16 "In7.Cu" signal "L8VCC")
		(18 "In8.Cu" signal "L9GND")
		(20 "In9.Cu" signal "L10")
		(22 "In10.Cu" signal "L11GND")
		(24 "In11.Cu" signal "L12")
		(26 "In12.Cu" signal "L13GND")
		(2 "B.Cu" signal "BOTTOM")
		(9 "F.Adhes" user "F.Adhesive")
		(11 "B.Adhes" user "B.Adhesive")
		(13 "F.Paste" user "Package Geometry/Pastemask Top")
		(15 "B.Paste" user "Package Geometry/Pastemask Bottom")
		(5 "F.SilkS" user "Ref Des/Silkscreen Top")
		(7 "B.SilkS" user "Ref Des/Silkscreen Bottom")
		(1 "F.Mask" user "Board Geometry/Soldermask Top")
		(3 "B.Mask" user "Board Geometry/Soldermask Bottom")
		(17 "Dwgs.User" user "User.Drawings")
		(19 "Cmts.User" user "User.Comments")
		(21 "Eco1.User" user "User.Eco1")
		(23 "Eco2.User" user "User.Eco2")
		(25 "Edge.Cuts" user "Board Geometry/Outline")
		(27 "Margin" user)
		(31 "F.CrtYd" user "Package Geometry/Place Bound Top")
		(29 "B.CrtYd" user "Package Geometry/Place Bound Bottom")
		(35 "F.Fab" user "Ref Des/Assembly Top")
		(33 "B.Fab" user "Ref Des/Assembly Bottom")
	)
	(footprint ""
		(layer "B.Cu")
		(at 97.270824 -83.74634 90)
		(property "Reference" "C8P5"
			(at 0 0 90)
			(layer "B.SilkS")
			(hide yes)
			(effects
				(font
					(size 1.27 1.27)
				)
				(justify mirror)
			)
		)
		(property "Value" ""
			(at 0 0 90)
			(layer "B.Fab")
			(effects
				(font
					(size 1.27 1.27)
				)
				(justify mirror)
			)
		)
		(duplicate_pad_numbers_are_jumpers no)
		(fp_poly
			(pts
				(xy 0.7239 -0.2159) (xy -0.7239 -0.2159) (xy -0.7239 1.9939) (xy 0.7239 1.9939)
			)
			(stroke
				(width 0)
				(type default)
			)
			(fill no)
			(layer "B.CrtYd")
		)
		(fp_line
			(start 0.7239 -0.2159)
			(end 0.7239 1.9939)
			(stroke
				(width 0.1)
				(type default)
			)
			(layer "B.Fab")
		)
		(fp_line
			(start -0.7239 -0.2159)
			(end 0.7239 -0.2159)
			(stroke
				(width 0.1)
				(type default)
			)
			(layer "B.Fab")
		)
		(fp_line
			(start 0.7239 1.9939)
			(end -0.7239 1.9939)
			(stroke
				(width 0.1)
				(type default)
			)
			(layer "B.Fab")
		)
		(fp_line
			(start -0.7239 1.9939)
			(end -0.7239 -0.2159)
			(stroke
				(width 0.1)
				(type default)
			)
			(layer "B.Fab")
		)
		(pad "1" smd rect
			(at 0 0 270)
			(size 1.27 1.016)
			(layers "B.Cu" "B.Mask" "B.Paste")
			(net "PVSA_CPU1")
		)
		(pad "2" smd rect
			(at 0 1.778 270)
			(size 1.27 1.016)
			(layers "B.Cu" "B.Mask" "B.Paste")
			(net "GND")
		)
		(zone
			(layer "B.Cu")
			(hatch none 0.5)
			(connect_pads
				(clearance 0)
			)
			(min_thickness 0.25)
			(keepout
				(tracks not_allowed)
				(vias allowed)
				(pads allowed)
				(copperpour not_allowed)
				(footprints allowed)
			)
			(placement
				(enabled no)
				(sheetname "")
			)
			(fill
				(thermal_gap 0.5)
				(thermal_bridge_width 0.5)
				(island_removal_mode 0)
			)
			(polygon
				(pts
					(xy 97.778824 -84.38134) (xy 97.778824 -83.11134) (xy 98.540824 -83.11134) (xy 98.540824 -84.38134)
				)
			)
		)
	)
	(footprint ""
		(layer "B.Cu")
		(at 334.01 -3.302 90)
		(property "Reference" "C3U5"
			(at 2.89433 4.572 0)
			(unlocked yes)
			(layer "B.SilkS")
			(effects
				(font
					(size 0.7874 0.5842)
					(thickness 0.1524)
				)
				(justify mirror)
			)
		)
		(property "Value" ""
			(at 0 0 90)
			(layer "B.Fab")
			(effects
				(font
					(size 1.27 1.27)
				)
				(justify mirror)
			)
		)
		(duplicate_pad_numbers_are_jumpers no)
		(fp_line
			(start 2.563114 -1.616456)
			(end 2.563114 1.633728)
			(stroke
				(width 0.1524)
				(type default)
			)
			(layer "B.SilkS")
		)
		(fp_line
			(start 1.6002 -1.616456)
			(end 2.563114 -1.616456)
			(stroke
				(width 0.1524)
				(type default)
			)
			(layer "B.SilkS")
		)
		(fp_line
			(start -1.6002 -1.616456)
			(end -2.504948 -1.616456)
			(stroke
				(width 0.1524)
				(type default)
			)
			(layer "B.SilkS")
		)
		(fp_line
			(start -2.504948 -1.616456)
			(end -2.504948 1.633728)
			(stroke
				(width 0.1524)
				(type default)
			)
			(layer "B.SilkS")
		)
		(fp_line
			(start 2.563114 1.633728)
			(end 1.6002 1.633728)
			(stroke
				(width 0.1524)
				(type default)
			)
			(layer "B.SilkS")
		)
		(fp_line
			(start -2.504948 1.633728)
			(end -1.6002 1.633728)
			(stroke
				(width 0.1524)
				(type default)
			)
			(layer "B.SilkS")
		)
		(fp_line
			(start 2.286 7.366)
			(end 2.286 1.632712)
			(stroke
				(width 0.1524)
				(type default)
			)
			(layer "B.SilkS")
		)
		(fp_line
			(start 2.286 7.366)
			(end 1.60147 7.366)
			(stroke
				(width 0.1524)
				(type default)
			)
			(layer "B.SilkS")
		)
		(fp_line
			(start -2.286 7.366)
			(end -2.286 1.63195)
			(stroke
				(width 0.1524)
				(type default)
			)
			(layer "B.SilkS")
		)
		(fp_line
			(start -2.286 7.366)
			(end -1.600708 7.366)
			(stroke
				(width 0.1524)
				(type default)
			)
			(layer "B.SilkS")
		)
		(fp_rect
			(start -2.286 -0.254)
			(end 2.286 7.366)
			(stroke
				(width 0)
				(type default)
			)
			(fill no)
			(layer "B.CrtYd")
		)
		(fp_line
			(start 2.286 -0.254)
			(end -2.286 -0.254)
			(stroke
				(width 0.1)
				(type default)
			)
			(layer "B.Fab")
		)
		(fp_line
			(start -2.286 -0.254)
			(end -2.286 7.366)
			(stroke
				(width 0.1)
				(type default)
			)
			(layer "B.Fab")
		)
		(fp_line
			(start 2.286 7.366)
			(end 2.286 -0.254)
			(stroke
				(width 0.1)
				(type default)
			)
			(layer "B.Fab")
		)
		(fp_line
			(start -2.286 7.366)
			(end 2.286 7.366)
			(stroke
				(width 0.1)
				(type default)
			)
			(layer "B.Fab")
		)
		(pad "1" smd rect
			(at 0 0 270)
			(size 2.54 3.048)
			(layers "B.Cu" "B.Mask" "B.Paste")
			(net "PVDDQ_ABC")
		)
		(pad "2" smd rect
			(at 0 7.112 270)
			(size 2.54 3.048)
			(layers "B.Cu" "B.Mask" "B.Paste")
			(net "GND")
		)
	)
	(footprint ""
		(layer "B.Cu")
		(at 427.4185 -24.13 90)
		(property "Reference" "R2N13"
			(at 0.8382 -0.67818 90)
			(unlocked yes)
			(layer "B.SilkS")
			(effects
				(font
					(size 0.4064 0.254)
					(thickness 0.1524)
				)
				(justify left mirror)
			)
		)
		(property "Value" ""
			(at 0 0 90)
			(layer "B.Fab")
			(effects
				(font
					(size 1.27 1.27)
				)
				(justify mirror)
			)
		)
		(duplicate_pad_numbers_are_jumpers no)
		(fp_poly
			(pts
				(xy 0.2794 -0.1016) (xy -0.2794 -0.1016) (xy -0.2794 0.9906) (xy 0.2794 0.9906)
			)
			(stroke
				(width 0)
				(type default)
			)
			(fill no)
			(layer "B.CrtYd")
		)
		(fp_line
			(start 0.2794 -0.1016)
			(end 0.2794 0.9906)
			(stroke
				(width 0.1)
				(type default)
			)
			(layer "B.Fab")
		)
		(fp_line
			(start -0.2794 -0.1016)
			(end 0.2794 -0.1016)
			(stroke
				(width 0.1)
				(type default)
			)
			(layer "B.Fab")
		)
		(fp_line
			(start 0.2794 0.9906)
			(end -0.2794 0.9906)
			(stroke
				(width 0.1)
				(type default)
			)
			(layer "B.Fab")
		)
		(fp_line
			(start -0.2794 0.9906)
			(end -0.2794 -0.1016)
			(stroke
				(width 0.1)
				(type default)
			)
			(layer "B.Fab")
		)
		(pad "1" smd rect
			(at 0 0 270)
			(size 0.508 0.508)
			(layers "B.Cu" "B.Mask" "B.Paste")
			(net "FM_BIOS_PREFRB2_GOOD")
		)
		(pad "2" smd rect
			(at 0 0.889 270)
			(size 0.508 0.508)
			(layers "B.Cu" "B.Mask" "B.Paste")
			(net "GND")
		)
		(zone
			(layer "B.Cu")
			(hatch none 0.5)
			(connect_pads
				(clearance 0)
			)
			(min_thickness 0.25)
			(keepout
				(tracks allowed)
				(vias not_allowed)
				(pads allowed)
				(copperpour not_allowed)
				(footprints allowed)
			)
			(placement
				(enabled no)
				(sheetname "")
			)
			(fill
				(thermal_gap 0.5)
				(thermal_bridge_width 0.5)
				(island_removal_mode 0)
			)
			(polygon
				(pts
					(xy 427.6725 -24.384) (xy 427.6725 -23.876) (xy 428.0535 -23.876) (xy 428.0535 -24.384)
				)
			)
		)
		(zone
			(layer "B.Cu")
			(hatch none 0.5)
			(connect_pads
				(clearance 0)
			)
			(min_thickness 0.25)
			(keepout
				(tracks not_allowed)
				(vias allowed)
				(pads allowed)
				(copperpour not_allowed)
				(footprints allowed)
			)
			(placement
				(enabled no)
				(sheetname "")
			)
			(fill
				(thermal_gap 0.5)
				(thermal_bridge_width 0.5)
				(island_removal_mode 0)
			)
			(polygon
				(pts
					(xy 428.0535 -24.384) (xy 428.0535 -23.876) (xy 427.6725 -23.876) (xy 427.6725 -24.384)
				)
			)
		)
	)
	(footprint ""
		(layer "B.Cu")
		(at 349.631 -27.9654 180)
		(property "Reference" "C3T10"
			(at 0 0 0)
			(layer "B.SilkS")
			(hide yes)
			(effects
				(font
					(size 1.27 1.27)
				)
				(justify mirror)
			)
		)
		(property "Value" ""
			(at 0 0 0)
			(layer "B.Fab")
			(effects
				(font
					(size 1.27 1.27)
				)
				(justify mirror)
			)
		)
		(duplicate_pad_numbers_are_jumpers no)
		(fp_poly
			(pts
				(xy -0.3048 -0.1016) (xy -0.3048 0.9906) (xy 0.3048 0.9906) (xy 0.3048 -0.1016)
			)
			(stroke
				(width 0)
				(type default)
			)
			(fill no)
			(layer "B.CrtYd")
		)
		(fp_line
			(start 0.3048 0.9906)
			(end -0.3048 0.9906)
			(stroke
				(width 0.1)
				(type default)
			)
			(layer "B.Fab")
		)
		(fp_line
			(start 0.3048 -0.1016)
			(end 0.3048 0.9906)
			(stroke
				(width 0.1)
				(type default)
			)
			(layer "B.Fab")
		)
		(fp_line
			(start -0.3048 0.9906)
			(end -0.3048 -0.1016)
			(stroke
				(width 0.1)
				(type default)
			)
			(layer "B.Fab")
		)
		(fp_line
			(start -0.3048 -0.1016)
			(end 0.3048 -0.1016)
			(stroke
				(width 0.1)
				(type default)
			)
			(layer "B.Fab")
		)
		(pad "1" smd rect
			(at 0 0)
			(size 0.508 0.508)
			(layers "B.Cu" "B.Mask" "B.Paste")
			(net "VR_FET_SW_P12V_STBY_PVPP_ABC")
		)
		(pad "2" smd rect
			(at 0 0.889)
			(size 0.508 0.508)
			(layers "B.Cu" "B.Mask" "B.Paste")
			(net "GND")
		)
		(zone
			(layer "B.Cu")
			(hatch none 0.5)
			(connect_pads
				(clearance 0)
			)
			(min_thickness 0.25)
			(keepout
				(tracks not_allowed)
				(vias allowed)
				(pads allowed)
				(copperpour not_allowed)
				(footprints allowed)
			)
			(placement
				(enabled no)
				(sheetname "")
			)
			(fill
				(thermal_gap 0.5)
				(thermal_bridge_width 0.5)
				(island_removal_mode 0)
			)
			(polygon
				(pts
					(xy 349.377 -28.6004) (xy 349.885 -28.6004) (xy 349.885 -28.2194) (xy 349.377 -28.2194)
				)
			)
		)
		(zone
			(layer "B.Cu")
			(hatch none 0.5)
			(connect_pads
				(clearance 0)
			)
			(min_thickness 0.25)
			(keepout
				(tracks allowed)
				(vias not_allowed)
				(pads allowed)
				(copperpour not_allowed)
				(footprints allowed)
			)
			(placement
				(enabled no)
				(sheetname "")
			)
			(fill
				(thermal_gap 0.5)
				(thermal_bridge_width 0.5)
				(island_removal_mode 0)
			)
			(polygon
				(pts
					(xy 349.377 -28.2194) (xy 349.885 -28.2194) (xy 349.885 -28.6004) (xy 349.377 -28.6004)
				)
			)
		)
	)
	(footprint ""
		(layer "B.Cu")
		(at 173.736 -87.757)
		(property "Reference" "R6P1"
			(at 0 0 0)
			(layer "B.SilkS")
			(hide yes)
			(effects
				(font
					(size 1.27 1.27)
				)
				(justify mirror)
			)
		)
		(property "Value" ""
			(at 0 0 0)
			(layer "B.Fab")
			(effects
				(font
					(size 1.27 1.27)
				)
				(justify mirror)
			)
		)
		(duplicate_pad_numbers_are_jumpers no)
		(fp_poly
			(pts
				(xy 0.2794 -0.1016) (xy -0.2794 -0.1016) (xy -0.2794 0.9906) (xy 0.2794 0.9906)
			)
			(stroke
				(width 0)
				(type default)
			)
			(fill no)
			(layer "B.CrtYd")
		)
		(fp_line
			(start -0.2794 -0.1016)
			(end 0.2794 -0.1016)
			(stroke
				(width 0.1)
				(type default)
			)
			(layer "B.Fab")
		)
		(fp_line
			(start -0.2794 0.9906)
			(end -0.2794 -0.1016)
			(stroke
				(width 0.1)
				(type default)
			)
			(layer "B.Fab")
		)
		(fp_line
			(start 0.2794 -0.1016)
			(end 0.2794 0.9906)
			(stroke
				(width 0.1)
				(type default)
			)
			(layer "B.Fab")
		)
		(fp_line
			(start 0.2794 0.9906)
			(end -0.2794 0.9906)
			(stroke
				(width 0.1)
				(type default)
			)
			(layer "B.Fab")
		)
		(pad "1" smd rect
			(at 0 0 180)
			(size 0.508 0.508)
			(layers "B.Cu" "B.Mask" "B.Paste")
			(net "CLK_100M_CPU0_RC_REFCLK0_DP")
		)
		(pad "2" smd rect
			(at 0 0.889 180)
			(size 0.508 0.508)
			(layers "B.Cu" "B.Mask" "B.Paste")
			(net "GND")
		)
		(zone
			(layer "B.Cu")
			(hatch none 0.5)
			(connect_pads
				(clearance 0)
			)
			(min_thickness 0.25)
			(keepout
				(tracks allowed)
				(vias not_allowed)
				(pads allowed)
				(copperpour not_allowed)
				(footprints allowed)
			)
			(placement
				(enabled no)
				(sheetname "")
			)
			(fill
				(thermal_gap 0.5)
				(thermal_bridge_width 0.5)
				(island_removal_mode 0)
			)
			(polygon
				(pts
					(xy 173.99 -87.503) (xy 173.482 -87.503) (xy 173.482 -87.122) (xy 173.99 -87.122)
				)
			)
		)
		(zone
			(layer "B.Cu")
			(hatch none 0.5)
			(connect_pads
				(clearance 0)
			)
			(min_thickness 0.25)
			(keepout
				(tracks not_allowed)
				(vias allowed)
				(pads allowed)
				(copperpour not_allowed)
				(footprints allowed)
			)
			(placement
				(enabled no)
				(sheetname "")
			)
			(fill
				(thermal_gap 0.5)
				(thermal_bridge_width 0.5)
				(island_removal_mode 0)
			)
			(polygon
				(pts
					(xy 173.99 -87.122) (xy 173.482 -87.122) (xy 173.482 -87.503) (xy 173.99 -87.503)
				)
			)
		)
	)
	(footprint ""
		(layer "B.Cu")
		(at 480.037902 -55.990998)
		(property "Reference" "R8E23"
			(at 0 0 0)
			(layer "B.SilkS")
			(hide yes)
			(effects
				(font
					(size 1.27 1.27)
				)
				(justify mirror)
			)
		)
		(property "Value" ""
			(at 0 0 0)
			(layer "B.Fab")
			(effects
				(font
					(size 1.27 1.27)
				)
				(justify mirror)
			)
		)
		(duplicate_pad_numbers_are_jumpers no)
		(fp_poly
			(pts
				(xy 0.2794 -0.1016) (xy -0.2794 -0.1016) (xy -0.2794 0.9906) (xy 0.2794 0.9906)
			)
			(stroke
				(width 0)
				(type default)
			)
			(fill no)
			(layer "B.CrtYd")
		)
		(fp_line
			(start -0.2794 -0.1016)
			(end 0.2794 -0.1016)
			(stroke
				(width 0.1)
				(type default)
			)
			(layer "B.Fab")
		)
		(fp_line
			(start -0.2794 0.9906)
			(end -0.2794 -0.1016)
			(stroke
				(width 0.1)
				(type default)
			)
			(layer "B.Fab")
		)
		(fp_line
			(start 0.2794 -0.1016)
			(end 0.2794 0.9906)
			(stroke
				(width 0.1)
				(type default)
			)
			(layer "B.Fab")
		)
		(fp_line
			(start 0.2794 0.9906)
			(end -0.2794 0.9906)
			(stroke
				(width 0.1)
				(type default)
			)
			(layer "B.Fab")
		)
		(pad "1" smd rect
			(at 0 0 180)
			(size 0.508 0.508)
			(layers "B.Cu" "B.Mask" "B.Paste")
			(net "PU_TRI_STATE_EN")
		)
		(pad "2" smd rect
			(at 0 0.889 180)
			(size 0.508 0.508)
			(layers "B.Cu" "B.Mask" "B.Paste")
			(net "P3V3_STBY")
		)
		(zone
			(layer "B.Cu")
			(hatch none 0.5)
			(connect_pads
				(clearance 0)
			)
			(min_thickness 0.25)
			(keepout
				(tracks allowed)
				(vias not_allowed)
				(pads allowed)
				(copperpour not_allowed)
				(footprints allowed)
			)
			(placement
				(enabled no)
				(sheetname "")
			)
			(fill
				(thermal_gap 0.5)
				(thermal_bridge_width 0.5)
				(island_removal_mode 0)
			)
			(polygon
				(pts
					(xy 480.291902 -55.736998) (xy 479.783902 -55.736998) (xy 479.783902 -55.355998) (xy 480.291902 -55.355998)
				)
			)
		)
		(zone
			(layer "B.Cu")
			(hatch none 0.5)
			(connect_pads
				(clearance 0)
			)
			(min_thickness 0.25)
			(keepout
				(tracks not_allowed)
				(vias allowed)
				(pads allowed)
				(copperpour not_allowed)
				(footprints allowed)
			)
			(placement
				(enabled no)
				(sheetname "")
			)
			(fill
				(thermal_gap 0.5)
				(thermal_bridge_width 0.5)
				(island_removal_mode 0)
			)
			(polygon
				(pts
					(xy 480.291902 -55.355998) (xy 479.783902 -55.355998) (xy 479.783902 -55.736998) (xy 480.291902 -55.736998)
				)
			)
		)
	)
	(footprint ""
		(layer "B.Cu")
		(at 17.399 -89.281 -90)
		(property "Reference" "R9N14"
			(at 0 0 90)
			(layer "B.SilkS")
			(hide yes)
			(effects
				(font
					(size 1.27 1.27)
				)
				(justify mirror)
			)
		)
		(property "Value" ""
			(at 0 0 90)
			(layer "B.Fab")
			(effects
				(font
					(size 1.27 1.27)
				)
				(justify mirror)
			)
		)
		(duplicate_pad_numbers_are_jumpers no)
		(fp_poly
			(pts
				(xy 0.2794 -0.1016) (xy -0.2794 -0.1016) (xy -0.2794 0.9906) (xy 0.2794 0.9906)
			)
			(stroke
				(width 0)
				(type default)
			)
			(fill no)
			(layer "B.CrtYd")
		)
		(fp_line
			(start -0.2794 0.9906)
			(end -0.2794 -0.1016)
			(stroke
				(width 0.1)
				(type default)
			)
			(layer "B.Fab")
		)
		(fp_line
			(start 0.2794 0.9906)
			(end -0.2794 0.9906)
			(stroke
				(width 0.1)
				(type default)
			)
			(layer "B.Fab")
		)
		(fp_line
			(start -0.2794 -0.1016)
			(end 0.2794 -0.1016)
			(stroke
				(width 0.1)
				(type default)
			)
			(layer "B.Fab")
		)
		(fp_line
			(start 0.2794 -0.1016)
			(end 0.2794 0.9906)
			(stroke
				(width 0.1)
				(type default)
			)
			(layer "B.Fab")
		)
		(pad "1" smd rect
			(at 0 0 90)
			(size 0.508 0.508)
			(layers "B.Cu" "B.Mask" "B.Paste")
			(net "PVCCIO_CPU1")
		)
		(pad "2" smd rect
			(at 0 0.889 90)
			(size 0.508 0.508)
			(layers "B.Cu" "B.Mask" "B.Paste")
			(net "VR_PVCCIN_CPU1_VREN")
		)
		(zone
			(layer "B.Cu")
			(hatch none 0.5)
			(connect_pads
				(clearance 0)
			)
			(min_thickness 0.25)
			(keepout
				(tracks not_allowed)
				(vias allowed)
				(pads allowed)
				(copperpour not_allowed)
				(footprints allowed)
			)
			(placement
				(enabled no)
				(sheetname "")
			)
			(fill
				(thermal_gap 0.5)
				(thermal_bridge_width 0.5)
				(island_removal_mode 0)
			)
			(polygon
				(pts
					(xy 16.764 -89.027) (xy 16.764 -89.535) (xy 17.145 -89.535) (xy 17.145 -89.027)
				)
			)
		)
		(zone
			(layer "B.Cu")
			(hatch none 0.5)
			(connect_pads
				(clearance 0)
			)
			(min_thickness 0.25)
			(keepout
				(tracks allowed)
				(vias not_allowed)
				(pads allowed)
				(copperpour not_allowed)
				(footprints allowed)
			)
			(placement
				(enabled no)
				(sheetname "")
			)
			(fill
				(thermal_gap 0.5)
				(thermal_bridge_width 0.5)
				(island_removal_mode 0)
			)
			(polygon
				(pts
					(xy 17.145 -89.027) (xy 17.145 -89.535) (xy 16.764 -89.535) (xy 16.764 -89.027)
				)
			)
		)
	)
)
